(kicad_pcb
	(version 20260206)
	(generator "pcbnew")
	(generator_version "10.0")
	(general
		(thickness 1.6)
		(legacy_teardrops no)
	)
	(paper "A4")
	(title_block
		(title "Bryce Canyon_F.DPB_16315-1-OCP.brd")
		(comment 1 "Bryce Canyon / footprints 1328-1334 of 2223")
	)
	(layers
		(0 "F.Cu" signal "TOP")
		(4 "In1.Cu" signal "L2GND")
		(6 "In2.Cu" signal "L3")
		(8 "In3.Cu" signal "L4GND")
		(10 "In4.Cu" signal "L5")
		(12 "In5.Cu" signal "L6VCC")
		(14 "In6.Cu" signal "L7VCC")
		(16 "In7.Cu" signal "L8")
		(18 "In8.Cu" signal "L9GND")
		(20 "In9.Cu" signal "L10")
		(22 "In10.Cu" signal "L11GND")
		(2 "B.Cu" signal "BOTTOM")
		(9 "F.Adhes" user "F.Adhesive")
		(11 "B.Adhes" user "B.Adhesive")
		(13 "F.Paste" user "Package Geometry/Pastemask Top")
		(15 "B.Paste" user "Package Geometry/Pastemask Bottom")
		(5 "F.SilkS" user "Ref Des/Silkscreen Top")
		(7 "B.SilkS" user "Ref Des/Silkscreen Bottom")
		(1 "F.Mask" user "Board Geometry/Soldermask Top")
		(3 "B.Mask" user "Board Geometry/Soldermask Bottom")
		(17 "Dwgs.User" user "User.Drawings")
		(19 "Cmts.User" user "User.Comments")
		(21 "Eco1.User" user "User.Eco1")
		(23 "Eco2.User" user "User.Eco2")
		(25 "Edge.Cuts" user "Board Geometry/Outline")
		(27 "Margin" user)
		(31 "F.CrtYd" user "Package Geometry/Place Bound Top")
		(29 "B.CrtYd" user "Package Geometry/Place Bound Bottom")
		(35 "F.Fab" user "Ref Des/Assembly Top")
		(33 "B.Fab" user "Ref Des/Assembly Bottom")
	)
	(footprint ""
		(layer "F.Cu")
		(at 168.501568 -151.304244 -90)
		(property "Reference" "Q220"
			(at 0 0 270)
			(layer "F.SilkS")
			(hide yes)
			(effects
				(font
					(size 1.27 1.27)
				)
			)
		)
		(property "Value" "IRFH8201TRPBF-GP"
			(at -4.2164 -4.3688 270)
			(unlocked yes)
			(layer "F.Fab")
			(hide yes)
			(effects
				(font
					(size 1.016 1.016)
					(thickness 0.1524)
				)
			)
		)
		(property "Device Type" "PPAK-5PH42"
			(at -4.2164 -5.8928 270)
			(unlocked yes)
			(layer "F.Fab")
			(hide yes)
			(effects
				(font
					(size 1.016 1.016)
					(thickness 0.1524)
				)
			)
		)
		(duplicate_pad_numbers_are_jumpers no)
		(fp_line
			(start -3.0353 4.9276)
			(end -3.0353 3.9624)
			(stroke
				(width 0.3302)
				(type default)
			)
			(layer "F.SilkS")
		)
		(fp_line
			(start -1.9431 4.9276)
			(end -3.0353 4.9276)
			(stroke
				(width 0.3302)
				(type default)
			)
			(layer "F.SilkS")
		)
		(fp_line
			(start -2.8956 4.826)
			(end -2.8956 -2.794)
			(stroke
				(width 0.1524)
				(type default)
			)
			(layer "F.SilkS")
		)
		(fp_line
			(start 2.8956 4.826)
			(end -2.8956 4.826)
			(stroke
				(width 0.1524)
				(type default)
			)
			(layer "F.SilkS")
		)
		(fp_line
			(start -2.8956 -2.794)
			(end 2.8956 -2.794)
			(stroke
				(width 0.1524)
				(type default)
			)
			(layer "F.SilkS")
		)
		(fp_line
			(start 2.8956 -2.794)
			(end 2.8956 4.826)
			(stroke
				(width 0.1524)
				(type default)
			)
			(layer "F.SilkS")
		)
		(fp_poly
			(pts
				(xy -2.3622 5.334) (xy -1.4986 5.334) (xy -1.9304 4.9022)
			)
			(stroke
				(width 0)
				(type default)
			)
			(fill yes)
			(layer "F.SilkS")
		)
		(fp_poly
			(pts
				(xy -2.6416 2.54) (xy -0.3556 2.54) (xy -0.3556 0.3556) (xy -2.6416 0.3556)
			)
			(stroke
				(width 0)
				(type default)
			)
			(fill yes)
			(layer "F.Paste")
		)
		(fp_poly
			(pts
				(xy 0.3556 2.54) (xy 2.6416 2.54) (xy 2.6416 0.3556) (xy 0.3556 0.3556)
			)
			(stroke
				(width 0)
				(type default)
			)
			(fill yes)
			(layer "F.Paste")
		)
		(fp_poly
			(pts
				(xy -2.6416 -0.3556) (xy -0.3556 -0.3556) (xy -0.3556 -2.54) (xy -2.6416 -2.54)
			)
			(stroke
				(width 0)
				(type default)
			)
			(fill yes)
			(layer "F.Paste")
		)
		(fp_poly
			(pts
				(xy 0.3556 -0.3556) (xy 2.6416 -0.3556) (xy 2.6416 -2.54) (xy 0.3556 -2.54)
			)
			(stroke
				(width 0)
				(type default)
			)
			(fill yes)
			(layer "F.Paste")
		)
		(fp_rect
			(start -2.5781 3.9878)
			(end 2.5781 -2.1082)
			(stroke
				(width 0)
				(type default)
			)
			(fill no)
			(layer "F.CrtYd")
		)
		(fp_poly
			(pts
				(xy -3.1496 5.08) (xy -3.1496 -3.048) (xy 3.1496 -3.048) (xy 3.1496 3.9751) (xy 2.5781 3.9751) (xy 2.5781 -2.1082)
				(xy -2.5781 -2.1082) (xy -2.5781 3.9878) (xy 3.1496 3.9878) (xy 3.1496 5.08)
			)
			(stroke
				(width 0)
				(type default)
			)
			(fill no)
			(layer "F.CrtYd")
		)
		(fp_rect
			(start -3.1496 5.08)
			(end 3.1496 -3.048)
			(stroke
				(width 0)
				(type default)
			)
			(fill no)
			(layer "F.Fab")
		)
		(pad "1" smd rect
			(at -1.905 3.81 270)
			(size 0.762 1.524)
			(layers "F.Cu" "F.Mask" "F.Paste")
			(net "P12V_A_COMP")
		)
		(pad "2" smd rect
			(at -0.635 3.81 270)
			(size 0.762 1.524)
			(layers "F.Cu" "F.Mask" "F.Paste")
			(net "P12V_A_COMP")
		)
		(pad "3" smd rect
			(at 0.635 3.81 270)
			(size 0.762 1.524)
			(layers "F.Cu" "F.Mask" "F.Paste")
			(net "P12V_A_COMP")
		)
		(pad "4" smd rect
			(at 1.905 3.81 270)
			(size 0.762 1.524)
			(layers "F.Cu" "F.Mask" "F.Paste")
			(net "MB0_12V_CTRL_GATE1")
		)
		(pad "5" smd rect
			(at 0 0 270)
			(size 5.2832 5.08)
			(layers "F.Cu" "F.Mask" "F.Paste")
			(net "MB0_P12V_R")
		)
		(pad "6" smd rect
			(at 0.635 -2.032 270)
			(size 0.0254 0.0254)
			(layers "F.Cu" "F.Mask" "F.Paste")
			(net "MB0_P12V_R")
		)
		(pad "7" smd rect
			(at -0.635 -2.032 270)
			(size 0.0254 0.0254)
			(layers "F.Cu" "F.Mask" "F.Paste")
			(net "MB0_P12V_R")
		)
		(pad "8" smd rect
			(at -1.905 -2.032 270)
			(size 0.0254 0.0254)
			(layers "F.Cu" "F.Mask" "F.Paste")
			(net "MB0_P12V_R")
		)
	)
	(footprint ""
		(layer "F.Cu")
		(at 35.625024 -246.827548 90)
		(property "Reference" "C605"
			(at 0 0 90)
			(layer "F.SilkS")
			(hide yes)
			(effects
				(font
					(size 1.27 1.27)
				)
			)
		)
		(property "Value" "SCD1U16V2KX-3GP"
			(at 1.1811 -2.7051 90)
			(unlocked yes)
			(layer "F.Fab")
			(hide yes)
			(effects
				(font
					(size 1.016 1.016)
					(thickness 0.1524)
				)
			)
		)
		(property "Device Type" "C402H22"
			(at 1.1811 -4.2291 90)
			(unlocked yes)
			(layer "F.Fab")
			(hide yes)
			(effects
				(font
					(size 1.016 1.016)
					(thickness 0.1524)
				)
			)
		)
		(duplicate_pad_numbers_are_jumpers no)
		(fp_rect
			(start -0.4318 0.9525)
			(end 0.4318 -0.9525)
			(stroke
				(width 0)
				(type default)
			)
			(fill no)
			(layer "F.CrtYd")
		)
		(fp_rect
			(start -0.4318 0.9525)
			(end 0.4318 -0.9525)
			(stroke
				(width 0)
				(type default)
			)
			(fill no)
			(layer "F.Fab")
		)
		(pad "1" smd custom
			(at 0 -0.4445 90)
			(size 0.1524 0.1524)
			(layers "F.Cu" "F.Mask" "F.Paste")
			(net "P5V_A_VBST_RC")
			(options
				(clearance outline)
				(anchor circle)
			)
			(primitives
				(gr_poly
					(pts
						(arc
							(start 0.3048 -0.2032)
							(mid 0.275042 -0.275042)
							(end 0.2032 -0.3048)
						)
						(arc
							(start -0.2032 -0.3048)
							(mid -0.275042 -0.275042)
							(end -0.3048 -0.2032)
						)
						(arc
							(start -0.3048 0.2032)
							(mid -0.275042 0.275042)
							(end -0.2032 0.3048)
						)
						(arc
							(start 0.2032 0.3048)
							(mid 0.275042 0.275042)
							(end 0.3048 0.2032)
						)
					)
					(width 0)
					(fill yes)
				)
			)
		)
		(pad "2" smd custom
			(at 0 0.4445 90)
			(size 0.1524 0.1524)
			(layers "F.Cu" "F.Mask" "F.Paste")
			(net "P5V_A_LL")
			(options
				(clearance outline)
				(anchor circle)
			)
			(primitives
				(gr_poly
					(pts
						(arc
							(start 0.3048 -0.2032)
							(mid 0.275042 -0.275042)
							(end 0.2032 -0.3048)
						)
						(arc
							(start -0.2032 -0.3048)
							(mid -0.275042 -0.275042)
							(end -0.3048 -0.2032)
						)
						(arc
							(start -0.3048 0.2032)
							(mid -0.275042 0.275042)
							(end -0.2032 0.3048)
						)
						(arc
							(start 0.2032 0.3048)
							(mid 0.275042 0.275042)
							(end 0.3048 0.2032)
						)
					)
					(width 0)
					(fill yes)
				)
			)
		)
	)
	(footprint ""
		(layer "F.Cu")
		(at 464.9089 -172.851318 90)
		(property "Reference" "C335"
			(at 0 0 90)
			(layer "F.SilkS")
			(hide yes)
			(effects
				(font
					(size 1.27 1.27)
				)
			)
		)
		(property "Value" "SCD033U25V2KX-GP"
			(at 1.1811 -2.7051 90)
			(unlocked yes)
			(layer "F.Fab")
			(hide yes)
			(effects
				(font
					(size 1.016 1.016)
					(thickness 0.1524)
				)
			)
		)
		(property "Device Type" "C402H22"
			(at 1.1811 -4.2291 90)
			(unlocked yes)
			(layer "F.Fab")
			(hide yes)
			(effects
				(font
					(size 1.016 1.016)
					(thickness 0.1524)
				)
			)
		)
		(duplicate_pad_numbers_are_jumpers no)
		(fp_rect
			(start -0.4318 0.9525)
			(end 0.4318 -0.9525)
			(stroke
				(width 0)
				(type default)
			)
			(fill no)
			(layer "F.CrtYd")
		)
		(fp_rect
			(start -0.4318 0.9525)
			(end 0.4318 -0.9525)
			(stroke
				(width 0)
				(type default)
			)
			(fill no)
			(layer "F.Fab")
		)
		(pad "1" smd custom
			(at 0 -0.4445 90)
			(size 0.1524 0.1524)
			(layers "F.Cu" "F.Mask" "F.Paste")
			(net "P12V_A")
			(options
				(clearance outline)
				(anchor circle)
			)
			(primitives
				(gr_poly
					(pts
						(arc
							(start 0.3048 -0.2032)
							(mid 0.275042 -0.275042)
							(end 0.2032 -0.3048)
						)
						(arc
							(start -0.2032 -0.3048)
							(mid -0.275042 -0.275042)
							(end -0.3048 -0.2032)
						)
						(arc
							(start -0.3048 0.2032)
							(mid -0.275042 0.275042)
							(end -0.2032 0.3048)
						)
						(arc
							(start 0.2032 0.3048)
							(mid 0.275042 0.275042)
							(end 0.3048 0.2032)
						)
					)
					(width 0)
					(fill yes)
				)
			)
		)
		(pad "2" smd custom
			(at 0 0.4445 90)
			(size 0.1524 0.1524)
			(layers "F.Cu" "F.Mask" "F.Paste")
			(net "SW_HDD_N22")
			(options
				(clearance outline)
				(anchor circle)
			)
			(primitives
				(gr_poly
					(pts
						(arc
							(start 0.3048 -0.2032)
							(mid 0.275042 -0.275042)
							(end 0.2032 -0.3048)
						)
						(arc
							(start -0.2032 -0.3048)
							(mid -0.275042 -0.275042)
							(end -0.3048 -0.2032)
						)
						(arc
							(start -0.3048 0.2032)
							(mid -0.275042 0.275042)
							(end -0.2032 0.3048)
						)
						(arc
							(start 0.2032 0.3048)
							(mid 0.275042 0.275042)
							(end 0.3048 0.2032)
						)
					)
					(width 0)
					(fill yes)
				)
			)
		)
	)
	(footprint ""
		(layer "F.Cu")
		(at 384.734562 -43.660568 -90)
		(property "Reference" "C455"
			(at 0 0 270)
			(layer "F.SilkS")
			(hide yes)
			(effects
				(font
					(size 1.27 1.27)
				)
			)
		)
		(property "Value" "SCD01U16V1KX-GP"
			(at -2.8321 -1.7399 270)
			(unlocked yes)
			(layer "F.Fab")
			(hide yes)
			(effects
				(font
					(size 1.016 1.016)
					(thickness 0.1524)
				)
			)
		)
		(property "Device Type" "C0201H13"
			(at -2.8321 -3.2639 270)
			(unlocked yes)
			(layer "F.Fab")
			(hide yes)
			(effects
				(font
					(size 1.016 1.016)
					(thickness 0.1524)
				)
			)
		)
		(duplicate_pad_numbers_are_jumpers no)
		(fp_rect
			(start -0.2794 0.6477)
			(end 0.2794 -0.6477)
			(stroke
				(width 0)
				(type default)
			)
			(fill no)
			(layer "F.CrtYd")
		)
		(fp_rect
			(start -0.2794 0.6477)
			(end 0.2794 -0.6477)
			(stroke
				(width 0)
				(type default)
			)
			(fill no)
			(layer "F.Fab")
		)
		(pad "1" smd custom
			(at 0 -0.2794 270)
			(size 0.0762 0.0762)
			(layers "F.Cu" "F.Mask" "F.Paste")
			(net "SAS_HDD_RX_P32")
			(options
				(clearance outline)
				(anchor circle)
			)
			(primitives
				(gr_poly
					(pts
						(arc
							(start 0.1524 -0.127)
							(mid 0.137521 -0.162921)
							(end 0.1016 -0.1778)
						)
						(arc
							(start -0.1016 -0.1778)
							(mid -0.137521 -0.162921)
							(end -0.1524 -0.127)
						)
						(arc
							(start -0.1524 0.127)
							(mid -0.137521 0.162921)
							(end -0.1016 0.1778)
						)
						(arc
							(start 0.1016 0.1778)
							(mid 0.137521 0.162921)
							(end 0.1524 0.127)
						)
					)
					(width 0)
					(fill yes)
				)
			)
		)
		(pad "2" smd custom
			(at 0 0.2794 270)
			(size 0.0762 0.0762)
			(layers "F.Cu" "F.Mask" "F.Paste")
			(net "PHY_SCC_A_TO_DRV_A_32_DP")
			(options
				(clearance outline)
				(anchor circle)
			)
			(primitives
				(gr_poly
					(pts
						(arc
							(start 0.1524 -0.127)
							(mid 0.137521 -0.162921)
							(end 0.1016 -0.1778)
						)
						(arc
							(start -0.1016 -0.1778)
							(mid -0.137521 -0.162921)
							(end -0.1524 -0.127)
						)
						(arc
							(start -0.1524 0.127)
							(mid -0.137521 0.162921)
							(end -0.1016 0.1778)
						)
						(arc
							(start 0.1016 0.1778)
							(mid 0.137521 0.162921)
							(end 0.1524 0.127)
						)
					)
					(width 0)
					(fill yes)
				)
			)
		)
	)
	(footprint ""
		(layer "F.Cu")
		(at 413.016192 -281.115516 90)
		(property "Reference" "R585"
			(at 0 0 90)
			(layer "F.SilkS")
			(hide yes)
			(effects
				(font
					(size 1.27 1.27)
				)
			)
		)
		(property "Value" "4K7R2J-2-GP"
			(at 0.064008 -3.993896 90)
			(unlocked yes)
			(layer "F.Fab")
			(hide yes)
			(effects
				(font
					(size 1.016 1.016)
					(thickness 0.1524)
				)
			)
		)
		(property "Device Type" "R402H16"
			(at 0.064008 -5.517896 90)
			(unlocked yes)
			(layer "F.Fab")
			(hide yes)
			(effects
				(font
					(size 1.016 1.016)
					(thickness 0.1524)
				)
			)
		)
		(duplicate_pad_numbers_are_jumpers no)
		(fp_line
			(start 0.508 -0.9398)
			(end -0.508 -0.9398)
			(stroke
				(width 0.1524)
				(type default)
			)
			(layer "F.SilkS")
		)
		(fp_line
			(start -0.508 -0.9398)
			(end -0.508 0.9398)
			(stroke
				(width 0.1524)
				(type default)
			)
			(layer "F.SilkS")
		)
		(fp_rect
			(start -0.508 0.9398)
			(end 0.508 -0.9398)
			(stroke
				(width 0)
				(type default)
			)
			(fill no)
			(layer "F.CrtYd")
		)
		(fp_rect
			(start -0.508 0.9398)
			(end 0.508 -0.9398)
			(stroke
				(width 0)
				(type default)
			)
			(fill no)
			(layer "F.Fab")
		)
		(pad "1" smd custom
			(at 0 -0.4445 90)
			(size 0.1397 0.1397)
			(layers "F.Cu" "F.Mask" "F.Paste")
			(net "DRIVE_B_33_ACT")
			(options
				(clearance outline)
				(anchor circle)
			)
			(primitives
				(gr_poly
					(pts
						(arc
							(start -0.1778 -0.2794)
							(mid -0.249642 -0.249642)
							(end -0.2794 -0.1778)
						)
						(arc
							(start -0.2794 0.1778)
							(mid -0.249642 0.249642)
							(end -0.1778 0.2794)
						)
						(arc
							(start 0.1778 0.2794)
							(mid 0.249642 0.249642)
							(end 0.2794 0.1778)
						)
						(arc
							(start 0.2794 -0.1778)
							(mid 0.249642 -0.249642)
							(end 0.1778 -0.2794)
						)
					)
					(width 0)
					(fill yes)
				)
			)
		)
		(pad "2" smd custom
			(at 0 0.4445 90)
			(size 0.1397 0.1397)
			(layers "F.Cu" "F.Mask" "F.Paste")
			(net "GND")
			(options
				(clearance outline)
				(anchor circle)
			)
			(primitives
				(gr_poly
					(pts
						(arc
							(start -0.1778 -0.2794)
							(mid -0.249642 -0.249642)
							(end -0.2794 -0.1778)
						)
						(arc
							(start -0.2794 0.1778)
							(mid -0.249642 0.249642)
							(end -0.1778 0.2794)
						)
						(arc
							(start 0.1778 0.2794)
							(mid 0.249642 0.249642)
							(end 0.2794 0.1778)
						)
						(arc
							(start 0.2794 -0.1778)
							(mid 0.249642 -0.249642)
							(end 0.1778 -0.2794)
						)
					)
					(width 0)
					(fill yes)
				)
			)
		)
	)
	(footprint ""
		(layer "F.Cu")
		(at 416.284664 -44.219368 -90)
		(property "Reference" "C467"
			(at 0 0 270)
			(layer "F.SilkS")
			(hide yes)
			(effects
				(font
					(size 1.27 1.27)
				)
			)
		)
		(property "Value" "SCD01U16V1KX-GP"
			(at -2.8321 -1.7399 270)
			(unlocked yes)
			(layer "F.Fab")
			(hide yes)
			(effects
				(font
					(size 1.016 1.016)
					(thickness 0.1524)
				)
			)
		)
		(property "Device Type" "C0201H13"
			(at -2.8321 -3.2639 270)
			(unlocked yes)
			(layer "F.Fab")
			(hide yes)
			(effects
				(font
					(size 1.016 1.016)
					(thickness 0.1524)
				)
			)
		)
		(duplicate_pad_numbers_are_jumpers no)
		(fp_rect
			(start -0.2794 0.6477)
			(end 0.2794 -0.6477)
			(stroke
				(width 0)
				(type default)
			)
			(fill no)
			(layer "F.CrtYd")
		)
		(fp_rect
			(start -0.2794 0.6477)
			(end 0.2794 -0.6477)
			(stroke
				(width 0)
				(type default)
			)
			(fill no)
			(layer "F.Fab")
		)
		(pad "1" smd custom
			(at 0 -0.2794 270)
			(size 0.0762 0.0762)
			(layers "F.Cu" "F.Mask" "F.Paste")
			(net "SAS_HDD_RX_N33")
			(options
				(clearance outline)
				(anchor circle)
			)
			(primitives
				(gr_poly
					(pts
						(arc
							(start 0.1524 -0.127)
							(mid 0.137521 -0.162921)
							(end 0.1016 -0.1778)
						)
						(arc
							(start -0.1016 -0.1778)
							(mid -0.137521 -0.162921)
							(end -0.1524 -0.127)
						)
						(arc
							(start -0.1524 0.127)
							(mid -0.137521 0.162921)
							(end -0.1016 0.1778)
						)
						(arc
							(start 0.1016 0.1778)
							(mid 0.137521 0.162921)
							(end 0.1524 0.127)
						)
					)
					(width 0)
					(fill yes)
				)
			)
		)
		(pad "2" smd custom
			(at 0 0.2794 270)
			(size 0.0762 0.0762)
			(layers "F.Cu" "F.Mask" "F.Paste")
			(net "PHY_SCC_A_TO_DRV_A_33_DN")
			(options
				(clearance outline)
				(anchor circle)
			)
			(primitives
				(gr_poly
					(pts
						(arc
							(start 0.1524 -0.127)
							(mid 0.137521 -0.162921)
							(end 0.1016 -0.1778)
						)
						(arc
							(start -0.1016 -0.1778)
							(mid -0.137521 -0.162921)
							(end -0.1524 -0.127)
						)
						(arc
							(start -0.1524 0.127)
							(mid -0.137521 0.162921)
							(end -0.1016 0.1778)
						)
						(arc
							(start 0.1016 0.1778)
							(mid 0.137521 0.162921)
							(end 0.1524 0.127)
						)
					)
					(width 0)
					(fill yes)
				)
			)
		)
	)
	(footprint ""
		(layer "F.Cu")
		(at 78.323948 -47.183294 180)
		(property "Reference" "R744"
			(at 0 0 180)
			(layer "F.SilkS")
			(hide yes)
			(effects
				(font
					(size 1.27 1.27)
				)
			)
		)
		(property "Value" "200KR2F-L-GP"
			(at 0.064008 -3.993896 180)
			(unlocked yes)
			(layer "F.Fab")
			(hide yes)
			(effects
				(font
					(size 1.016 1.016)
					(thickness 0.1524)
				)
			)
		)
		(property "Device Type" "R402H16"
			(at 0.064008 -5.517896 180)
			(unlocked yes)
			(layer "F.Fab")
			(hide yes)
			(effects
				(font
					(size 1.016 1.016)
					(thickness 0.1524)
				)
			)
		)
		(duplicate_pad_numbers_are_jumpers no)
		(fp_line
			(start 0.508 -0.9398)
			(end -0.508 -0.9398)
			(stroke
				(width 0.1524)
				(type default)
			)
			(layer "F.SilkS")
		)
		(fp_line
			(start -0.508 -0.9398)
			(end -0.508 0.9398)
			(stroke
				(width 0.1524)
				(type default)
			)
			(layer "F.SilkS")
		)
		(fp_rect
			(start -0.508 0.9398)
			(end 0.508 -0.9398)
			(stroke
				(width 0)
				(type default)
			)
			(fill no)
			(layer "F.CrtYd")
		)
		(fp_rect
			(start -0.508 0.9398)
			(end 0.508 -0.9398)
			(stroke
				(width 0)
				(type default)
			)
			(fill no)
			(layer "F.Fab")
		)
		(pad "1" smd custom
			(at 0 -0.4445 180)
			(size 0.1397 0.1397)
			(layers "F.Cu" "F.Mask" "F.Paste")
			(net "SW_HDD_R26")
			(options
				(clearance outline)
				(anchor circle)
			)
			(primitives
				(gr_poly
					(pts
						(arc
							(start -0.1778 -0.2794)
							(mid -0.249642 -0.249642)
							(end -0.2794 -0.1778)
						)
						(arc
							(start -0.2794 0.1778)
							(mid -0.249642 0.249642)
							(end -0.1778 0.2794)
						)
						(arc
							(start 0.1778 0.2794)
							(mid 0.249642 0.249642)
							(end 0.2794 0.1778)
						)
						(arc
							(start 0.2794 -0.1778)
							(mid 0.249642 -0.249642)
							(end 0.1778 -0.2794)
						)
					)
					(width 0)
					(fill yes)
				)
			)
		)
		(pad "2" smd custom
			(at 0 0.4445 180)
			(size 0.1397 0.1397)
			(layers "F.Cu" "F.Mask" "F.Paste")
			(net "SW_HDD_N26")
			(options
				(clearance outline)
				(anchor circle)
			)
			(primitives
				(gr_poly
					(pts
						(arc
							(start -0.1778 -0.2794)
							(mid -0.249642 -0.249642)
							(end -0.2794 -0.1778)
						)
						(arc
							(start -0.2794 0.1778)
							(mid -0.249642 0.249642)
							(end -0.1778 0.2794)
						)
						(arc
							(start 0.1778 0.2794)
							(mid 0.249642 0.249642)
							(end 0.2794 0.1778)
						)
						(arc
							(start 0.2794 -0.1778)
							(mid 0.249642 -0.249642)
							(end 0.1778 -0.2794)
						)
					)
					(width 0)
					(fill yes)
				)
			)
		)
	)
)
